FILE_TYPE = CONNECTIVITY;
{Allegro Design Entry HDL 17.2-2016 S081 (4005846) 1/11/2022}
"PAGE_NUMBER" = 169;
0"NC";
1"GND\g";
2"GND\g";
3"GND\g";
4"GND\g";
5"GND\g";
6"P3V3_STBY\g";
7"GND\g";
8"GND\g";
9"P5V_STBY\g";
10"GND\g";
11"GND\g";
12"GND\g";
13"PVDDCR_CPU0_P0\g";
14"GND\g";
15"SW_PVDDCR_CPU0_P0_PH2";
16"SW_PVDDCR_CPU0_P0_SW2";
17"SW_PVDDCR_CPU0_P0_BOOT2";
18"SW_P12V_STBY_PVDDCR_CPU0_P0_FLT\g";
19"GND\g";
20"SW_PVDDCR_CPU0_P0_SW1";
21"SW_PVDDCR_CPU0_P0_PH1";
22"P12V_STBY\g";
23"SW_PVDDCR_CPU0_P0_BOOT1_RC";
24"GND\g";
25"GND\g";
26"IND_CPU0_P0_CPL2";
27"NC_PVDDCR_CPU0_P0_GL2_1";
28"NC_PVDDCR_CPU0_P0_GL1_1";
29"PVDDCR_CPU0_P0_IMON1";
30"PVDDCR_CPU0_P0_VCC1";
31"SW_PVDDCR_CPU0_P0_SW1_RC";
32"PVDDCR_CPU0_P0_VOS1";
33"GND\g";
34"SW_PVDDCR_CPU0_P0_SW2_RC";
35"GND\g";
36"NC_PVDDCR_CPU0_P0_GL1_2";
37"NC_PVDDCR_CPU0_P0_GL2_2";
38"PVDDCR_CPU0_P0_PVCC\g";
39"PVDDCR_CPU0_P0_VCC2";
40"NC_PVDDCR_CPU0_P0_DNC2";
41"PVDDCR_CPU0_P0_PWM2";
42"PVDDCR_CPU0_P0_TEMP0";
43"PVDDCR_CPU0_P0_IMON2";
44"PVDDCR_CPU0_P0_LSET2";
45"PVDDCR_CPU0_P0_VCCS";
46"PVDDCR_CPU0_P0_PVCC\g";
47"IND_CPU0_P0_CPL1";
48"PVDDCR_CPU0_P0\g";
49"SW_PVDDCR_CPU0_P0_BOOT2_RC";
50"IND_CPU0_P0_CPL1";
51"SW_P12V_STBY_PVDDCR_CPU0_P0_FLT\g";
52"PVDDCR_CPU0_P0_PWM1";
53"GND\g";
54"PVDDCR_CPU0_P0_VOS2";
55"PVDDCR_CPU0_P0\g";
56"IND_CPU0_P0_CPL5";
57"SW_PVDDCR_CPU0_P0_BOOT1";
58"NC_PVDDCR_CPU0_P0_DNC1";
59"PVDDCR_CPU0_P0_LSET1";
60"PVDDCR_CPU0_P0_TEMP0";
61"PVDDCR_CPU0_P0_VCCS";
%"UNIVERSAL_GND"
"1","(-4000,5000)","0","pure_quanta_power","I105";
;
CDS_LIB"pure_quanta_power"
HDL_POWER"GND";
"A"19;
%"Q_CAPP"
"1","(-2475,2900)","0","pure_quanta","I106";
;
LOCATION"PC495"
$SEC"1"
CDS_SEC"1"
VOLTAGE"4V"
PACK_TYPE"SMLF"
VALUE"220UF"
TOLERANCE"20%"
MATERIAL"SPCAP"
PART_NUMBER"CH122KM8801"
CDS_LIB"pure_quanta";
"A"
$PN"1"13;
"B"
$PN"2"14;
%"Q_CAPP"
"1","(-2800,2900)","0","pure_quanta","I107";
;
LOCATION"PC494"
$SEC"1"
CDS_SEC"1"
PACK_TYPE"SMLF"
VOLTAGE"4V"
MATERIAL"SPCAP"
PART_NUMBER"CH122KM8801"
TOLERANCE"20%"
VALUE"220UF"
CDS_LIB"pure_quanta";
"A"
$PN"1"13;
"B"
$PN"2"14;
%"VCC_CORE"
"1","(-1850,3200)","0","pure_quanta_power","I109";
;
HDL_POWER"PVDDCR_CPU0_P0"
CDS_LIB"pure_quanta_power";
"A"13;
%"Q_RES"
"1","(-7325,4150)","0","pure_quanta","I11";
;
LOCATION"PR320"
$SEC"1"
CDS_SEC"1"
PART_NUMBER"CS28872FB01"
MATERIAL"EMPTY"
WATTAGE"1/16W"
TOLERANCE"1%"
VALUE"8.87K"
PACK_TYPE"0402LF"
CDS_LIB"pure_quanta";
"B"
$PN"2"59;
"A"
$PN"1"3;
%"UNIVERSAL_GND"
"1","(-1850,2525)","0","pure_quanta_power","I110";
;
CDS_LIB"pure_quanta_power"
HDL_POWER"GND";
"A"14;
%"Q_CAPP"
"1","(-1875,2900)","0","pure_quanta","I112";
;
LOCATION"PC498"
$SEC"1"
CDS_SEC"1"
PACK_TYPE"SMLF"
VOLTAGE"4V"
VALUE"220UF"
TOLERANCE"20%"
PART_NUMBER"CH122KM8801"
MATERIAL"SPCAP"
CDS_LIB"pure_quanta";
"A"
$PN"1"13;
"B"
$PN"2"14;
%"Q_CAP"
"1","(-5525,5325)","0","pure_quanta","I113";
;
LOCATION"PC479_1"
$SEC"1"
CDS_SEC"1"
PART_NUMBER"CH4104K1B00"
MATERIAL"X7R"
TOLERANCE"10%"
VALUE"0.1UF"
VOLTAGE"25V"
PACK_TYPE"0402"
CDS_LIB"pure_quanta";
"B"
$PN"2"19;
"A"
$PN"1"51;
%"Q_CAP"
"1","(-5525,2575)","0","pure_quanta","I114";
;
LOCATION"PC480_2"
$SEC"1"
CDS_SEC"1"
MATERIAL"X7R"
PART_NUMBER"CH4104K1B00"
VALUE"0.1UF"
TOLERANCE"10%"
VOLTAGE"25V"
PACK_TYPE"0402"
CDS_LIB"pure_quanta";
"B"
$PN"2"53;
"A"
$PN"1"18;
%"Q_CAP"
"1","(-7625,2050)","0","pure_quanta","I115";
;
LOCATION"PC476"
$SEC"1"
CDS_SEC"1"
MATERIAL"X6S"
TOLERANCE"10%"
VALUE"2.2UF"
PART_NUMBER"CH5222KEB01"
VOLTAGE"10V"
PACK_TYPE"C0402"
CDS_LIB"pure_quanta";
"B"
$PN"2"1;
"A"
$PN"1"39;
%"UNIVERSAL_GND"
"1","(-7625,1850)","0","pure_quanta_power","I116";
;
CDS_LIB"pure_quanta_power"
HDL_POWER"GND";
"A"1;
%"UNIVERSAL_GND"
"1","(-7275,2300)","0","pure_quanta_power","I117";
;
CDS_LIB"pure_quanta_power"
HDL_POWER"GND";
"A"2;
%"Q_RES"
"2","(-7625,2550)","0","pure_quanta","I118";
;
LOCATION"PR319"
$SEC"1"
CDS_SEC"1"
WATTAGE"1/16W"
MATERIAL"CHIP"
TOLERANCE"1%"
VALUE"2.2"
PART_NUMBER"CS-2202FB00"
PACK_TYPE"0402LF"
CDS_LIB"pure_quanta";
"A"
$PN"1"38;
"B"
$PN"2"39;
%"Q_CAP"
"1","(-7275,2575)","0","pure_quanta","I119";
;
LOCATION"PC478_C0P0_2"
$SEC"1"
CDS_SEC"1"
MATERIAL"X6S"
TOLERANCE"10%"
VALUE"2.2UF"
PART_NUMBER"CH5222KEB01"
VOLTAGE"10V"
PACK_TYPE"C0402"
CDS_LIB"pure_quanta";
"B"
$PN"2"2;
"A"
$PN"1"38;
%"UNIVERSAL_GND"
"1","(-7650,3975)","0","pure_quanta_power","I12";
;
CDS_LIB"pure_quanta_power"
HDL_POWER"GND";
"A"3;
%"VCC_CORE"
"1","(-7625,2950)","0","pure_quanta_power","I120";
;
HDL_POWER"PVDDCR_CPU0_P0_PVCC"
CDS_LIB"pure_quanta_power";
"A"38;
%"ISL99390FRZTR5935"
"1","(-6175,4450)","0","pure_quanta","I121";
;
LOCATION"PU6"
$SEC"1"
CDS_SEC"1"
PART_TYPE"SMLF"
MATERIAL"IC"
VALUE"ISL99390FRZ-TR5935"
PART_NUMBER"AL099390004"
CDS_LMAN_SYM_OUTLINE"-300,700,250,-650"
CDS_LIB"pure_quanta"
NEEDS_NO_SIZE"TRUE";
"PGND2"
$PN"7_9-20_24"33;
"GL2"
$PN"41"27;
"GL1"
$PN"6"28;
"DNC"
$PN"31"58;
"EN"
$PN"35"30;
"PGND3"
$PN"40"33;
"VOS"
$PN"1"32;
"VIN2"
$PN"30"51;
"PGND1"
$PN"5"33;
"SW"
$PN"10_19"20;
"LSET"
$PN"37"59;
"IOUT"
$PN"38"29;
"TOUT_FLT"
$PN"36"60;
"PVCC"
$PN"4"46;
"PHASE"
$PN"32"21;
"VIN1"
$PN"25_29"51;
"BOOT"
$PN"33"57;
"AGND"
$PN"2"33;
"VCC"
$PN"3"30;
"REFIN"
$PN"39"61;
"PWM"
$PN"34"52;
%"ISL99390FRZTR5935"
"1","(-6150,1700)","0","pure_quanta","I122";
;
LOCATION"PU43"
$SEC"1"
CDS_SEC"1"
PART_TYPE"SMLF"
MATERIAL"IC"
VALUE"ISL99390FRZ-TR5935"
PART_NUMBER"AL099390004"
NEEDS_NO_SIZE"TRUE"
CDS_LIB"pure_quanta"
CDS_LMAN_SYM_OUTLINE"-300,700,250,-650";
"PGND2"
$PN"7_9-20_24"35;
"GL2"
$PN"41"37;
"GL1"
$PN"6"36;
"DNC"
$PN"31"40;
"EN"
$PN"35"39;
"PGND3"
$PN"40"35;
"VOS"
$PN"1"54;
"VIN2"
$PN"30"18;
"PGND1"
$PN"5"35;
"SW"
$PN"10_19"16;
"LSET"
$PN"37"44;
"IOUT"
$PN"38"43;
"TOUT_FLT"
$PN"36"42;
"PVCC"
$PN"4"38;
"PHASE"
$PN"32"15;
"VIN1"
$PN"25_29"18;
"BOOT"
$PN"33"17;
"AGND"
$PN"2"35;
"VCC"
$PN"3"39;
"REFIN"
$PN"39"45;
"PWM"
$PN"34"41;
%"Q_CAPP"
"1","(-3150,2900)","0","pure_quanta","I123";
;
LOCATION"PC108"
$SEC"1"
CDS_SEC"1"
VOLTAGE"4V"
PACK_TYPE"SMLF"
TOLERANCE"20%"
MATERIAL"SPCAP"
PART_NUMBER"CH122KM8801"
VALUE"220UF"
CDS_LIB"pure_quanta";
"A"
$PN"1"13;
"B"
$PN"2"14;
%"Q_CAP"
"1","(-4800,4275)","0","pure_quanta","I125";
;
LOCATION"PC178"
$SEC"1"
CDS_SEC"1"
MATERIAL"EMPTY"
TOLERANCE"10%"
VALUE"560PF"
PART_NUMBER"CH1566K1B09"
VOLTAGE"50V"
PACK_TYPE"C0402"
CDS_LIB"pure_quanta";
"B"
$PN"2"31;
"A"
$PN"1"20;
%"Q_RES"
"2","(-4800,3825)","0","pure_quanta","I126";
;
LOCATION"PR495"
$SEC"1"
CDS_SEC"1"
WATTAGE"1/8W"
MATERIAL"EMPTY"
TOLERANCE"1%"
VALUE"1.5"
PART_NUMBER"CS-1504FB00"
PACK_TYPE"0402LF"
CDS_LIB"pure_quanta";
"A"
$PN"1"31;
"B"
$PN"2"4;
%"UNIVERSAL_GND"
"1","(-4800,3600)","0","pure_quanta_power","I127";
;
CDS_LIB"pure_quanta_power"
HDL_POWER"GND";
"A"4;
%"Q_CAP"
"1","(-4625,1525)","0","pure_quanta","I128";
;
LOCATION"PC179"
$SEC"1"
CDS_SEC"1"
PACK_TYPE"C0402"
MATERIAL"EMPTY"
TOLERANCE"10%"
VALUE"560PF"
PART_NUMBER"CH1566K1B09"
VOLTAGE"50V"
CDS_LIB"pure_quanta";
"B"
$PN"2"34;
"A"
$PN"1"16;
%"UNIVERSAL_GND"
"1","(-4625,850)","0","pure_quanta_power","I129";
;
CDS_LIB"pure_quanta_power"
HDL_POWER"GND";
"A"5;
%"Q_CAP"
"1","(-8000,4175)","0","pure_quanta","I13";
;
LOCATION"PC473_1"
$SEC"1"
CDS_SEC"1"
MATERIAL"X7R"
TOLERANCE"10%"
VALUE"0.1UF"
PART_NUMBER"CH4104K1B00"
VOLTAGE"25V"
PACK_TYPE"0402"
CDS_LIB"pure_quanta";
"B"
$PN"2"7;
"A"
$PN"1"61;
%"Q_RES"
"2","(-4625,1075)","0","pure_quanta","I130";
;
LOCATION"PR496"
$SEC"1"
CDS_SEC"1"
WATTAGE"1/8W"
MATERIAL"EMPTY"
TOLERANCE"1%"
VALUE"1.5"
PART_NUMBER"CS-1504FB00"
PACK_TYPE"0402LF"
CDS_LIB"pure_quanta";
"A"
$PN"1"34;
"B"
$PN"2"5;
%"Q_RES"
"1","(-8600,5725)","1","pure_quanta","I132";
;
LOCATION"PR445"
$SEC"1"
CDS_SEC"1"
WATTAGE"1/16W"
MATERIAL"CHIP"
TOLERANCE"5%"
VALUE"0"
PACK_TYPE"0402LF"
PART_NUMBER"CS00002JB38"
CDS_LIB"pure_quanta";
"B"
$PN"2"9;
"A"
$PN"1"46;
%"Q_RES"
"1","(-8250,5725)","1","pure_quanta","I133";
;
LOCATION"PR446"
$SEC"1"
CDS_SEC"1"
WATTAGE"1/16W"
MATERIAL"EMPTY"
TOLERANCE"5%"
VALUE"0"
PART_NUMBER"CS00002JB38"
PACK_TYPE"0402LF"
CDS_LIB"pure_quanta";
"B"
$PN"2"6;
"A"
$PN"1"46;
%"VCC_CORE"
"1","(-8250,5925)","0","pure_quanta_power","I134";
;
HDL_POWER"P3V3_STBY"
CDS_LIB"pure_quanta_power";
"A"6;
%"VCC_CORE"
"1","(-7775,5925)","0","pure_quanta_power","I135";
;
HDL_POWER"PVDDCR_CPU0_P0_PVCC"
CDS_LIB"pure_quanta_power";
"A"46;
%"Q_RES"
"2","(-750,4250)","0","pure_quanta","I136";
;
LOCATION"PR447"
$SEC"1"
CDS_SEC"1"
WATTAGE"1/16W"
MATERIAL"CHIP"
TOLERANCE"1%"
VALUE"1K"
PART_NUMBER"TMP_QCS21002FB24"
PACK_TYPE"0402LF"
CDS_LIB"pure_quanta";
"A"
$PN"1"55;
"B"
$PN"2"24;
%"UNIVERSAL_GND"
"1","(-8000,3900)","0","pure_quanta_power","I14";
;
CDS_LIB"pure_quanta_power"
HDL_POWER"GND";
"A"7;
%"UNIVERSAL_GND"
"1","(-5600,3725)","0","pure_quanta_power","I15";
;
CDS_LIB"pure_quanta_power"
HDL_POWER"GND";
"A"33;
%"Q_RES"
"1","(-4825,4800)","0","pure_quanta","I16";
;
LOCATION"PR322"
$SEC"1"
CDS_SEC"1"
PACK_TYPE"0402LF"
MATERIAL"CHIP"
WATTAGE"1/16W"
TOLERANCE"1%"
VALUE"4.7"
PART_NUMBER"CS-4702FB19"
CDS_LIB"pure_quanta";
"B"
$PN"2"23;
"A"
$PN"1"57;
%"Q_CAP"
"1","(-3975,4675)","0","pure_quanta","I17";
;
LOCATION"PC489"
$SEC"1"
CDS_SEC"1"
PART_NUMBER"CH4223K1B00"
PACK_TYPE"0402"
MATERIAL"X7R"
TOLERANCE"10%"
VALUE"0.22UF"
VOLTAGE"16V"
CDS_LIB"pure_quanta";
"B"
$PN"2"21;
"A"
$PN"1"23;
%"Q_CAP"
"1","(-4250,5325)","0","pure_quanta","I18";
;
LOCATION"PC487_1"
$SEC"1"
CDS_SEC"1"
MATERIAL"X6S"
TOLERANCE"10%"
VALUE"10UF"
VOLTAGE"25V"
PART_NUMBER"CH6104KEA00"
PACK_TYPE"C0805"
CDS_LIB"pure_quanta";
"B"
$PN"2"19;
"A"
$PN"1"51;
%"Q_CAP"
"1","(-4550,5325)","0","pure_quanta","I19";
;
LOCATION"PC485_1"
$SEC"1"
CDS_SEC"1"
PACK_TYPE"C0805"
MATERIAL"X6S"
TOLERANCE"10%"
VALUE"10UF"
PART_NUMBER"CH6104KEA00"
VOLTAGE"25V"
CDS_LIB"pure_quanta";
"B"
$PN"2"19;
"A"
$PN"1"51;
%"Q_CAP"
"1","(-7600,5300)","0","pure_quanta","I2";
;
LOCATION"PC477_C0P0_1"
$SEC"1"
CDS_SEC"1"
PACK_TYPE"C0402"
MATERIAL"X6S"
TOLERANCE"10%"
VALUE"2.2UF"
PART_NUMBER"CH5222KEB01"
VOLTAGE"10V"
CDS_LIB"pure_quanta";
"B"
$PN"2"8;
"A"
$PN"1"46;
%"Q_CAP"
"1","(-4875,5325)","0","pure_quanta","I20";
;
LOCATION"PC483_1"
$SEC"1"
CDS_SEC"1"
MATERIAL"X6S"
TOLERANCE"10%"
VALUE"10UF"
PART_NUMBER"CH6104KEA00"
VOLTAGE"25V"
PACK_TYPE"C0805"
CDS_LIB"pure_quanta";
"B"
$PN"2"19;
"A"
$PN"1"51;
%"Q_CAP"
"1","(-5200,5325)","0","pure_quanta","I21";
;
LOCATION"PC481_1"
$SEC"1"
CDS_SEC"1"
PACK_TYPE"C0402"
MATERIAL"X6S"
TOLERANCE"10%"
VALUE"1UF"
PART_NUMBER"CH5104KEB02"
VOLTAGE"25V"
CDS_LIB"pure_quanta";
"B"
$PN"2"19;
"A"
$PN"1"51;
%"Q_INDUCTOR"
"1","(-3050,5525)","0","pure_quanta","I24";
;
LOCATION"PL53"
$SEC"1"
CDS_SEC"1"
MATERIAL"IND"
PART_NUMBER"CVA50^0MZ09"
VALUE"50NH/86A"
PACK_TYPE"SMLF"
NEEDS_NO_SIZE"TRUE"
CDS_LIB"pure_quanta";
"1"
$PN"1"51;
"2"
$PN"2"22;
%"VCC_CORE"
"1","(-4000,5600)","0","pure_quanta_power","I25";
;
HDL_POWER"SW_P12V_STBY_PVDDCR_CPU0_P0_FLT"
CDS_LIB"pure_quanta_power";
"A"51;
%"Q_CAPP"
"1","(-3925,5325)","0","pure_quanta","I26";
;
LOCATION"PC491"
$SEC"1"
CDS_SEC"1"
TOLERANCE"20%"
VALUE"220UF"
PACK_TYPE"THLF"
MATERIAL"OSCON"
PART_NUMBER"CC72204MD02"
VOLTAGE"25V"
CDS_LIB"pure_quanta";
"A"
$PN"1"51;
"B"
$PN"2"19;
%"Q_CAPP"
"1","(-3500,5325)","0","pure_quanta","I27";
;
LOCATION"PC492"
$SEC"1"
CDS_SEC"1"
PART_NUMBER"CC72204MD02"
PACK_TYPE"THLF"
MATERIAL"OSCON"
TOLERANCE"20%"
VALUE"220UF"
VOLTAGE"25V"
CDS_LIB"pure_quanta";
"A"
$PN"1"51;
"B"
$PN"2"19;
%"Q_RES"
"2","(-7950,5300)","0","pure_quanta","I3";
;
LOCATION"PR318"
$SEC"1"
CDS_SEC"1"
PART_NUMBER"CS-2202FB00"
WATTAGE"1/16W"
MATERIAL"CHIP"
TOLERANCE"1%"
VALUE"2.2"
PACK_TYPE"0402LF"
CDS_LIB"pure_quanta";
"A"
$PN"1"46;
"B"
$PN"2"30;
%"VCC_CORE"
"1","(-2750,5600)","0","pure_quanta_power","I30";
;
HDL_POWER"P12V_STBY"
CDS_LIB"pure_quanta_power";
"A"22;
%"Q_INDUCTOR4P_14"
"1","(-3225,4325)","0","pure_quanta","I31";
;
LOCATION"PL51"
$SEC"1"
CDS_SEC"1"
PART_TYPE"SMLF"
PART_NUMBER"CV+15^0TZ04"
MATERIAL"IND"
VALUE"150NH"
NEEDS_NO_SIZE"TRUE"
CDS_LIB"pure_quanta";
"1"
$PN"1"20;
"4"
$PN"4"55;
"3"
$PN"3"47;
"2"
$PN"2"56;
%"Q_CAP"
"1","(-1150,4275)","0","pure_quanta","I32";
;
LOCATION"PC502_1"
$SEC"1"
CDS_SEC"1"
MATERIAL"X6S"
TOLERANCE"20%"
VALUE"22UF"
VOLTAGE"4V"
PACK_TYPE"0805"
CDS_LIB"pure_quanta"
PART_NUMBER"TMP_QCH622KMEA01";
"B"
$PN"2"24;
"A"
$PN"1"55;
%"Q_CAP"
"1","(-1600,4275)","0","pure_quanta","I33";
;
LOCATION"PC500_1"
$SEC"1"
CDS_SEC"1"
MATERIAL"X6S"
TOLERANCE"20%"
VALUE"22UF"
PART_NUMBER"TMP_QCH622KMEA01"
VOLTAGE"4V"
PACK_TYPE"0805"
CDS_LIB"pure_quanta";
"B"
$PN"2"24;
"A"
$PN"1"55;
%"Q_CAP"
"1","(-1975,4275)","0","pure_quanta","I35";
;
LOCATION"PC497"
$SEC"1"
CDS_SEC"1"
MATERIAL"X7R"
TOLERANCE"10%"
VALUE"0.1UF"
PART_NUMBER"CH4104K1B00"
VOLTAGE"25V"
PACK_TYPE"0402"
CDS_LIB"pure_quanta";
"B"
$PN"2"24;
"A"
$PN"1"55;
%"UNIVERSAL_GND"
"1","(-750,3900)","0","pure_quanta_power","I36";
;
CDS_LIB"pure_quanta_power"
HDL_POWER"GND";
"A"24;
%"VCC_CORE"
"1","(-750,4625)","0","pure_quanta_power","I37";
;
HDL_POWER"PVDDCR_CPU0_P0"
CDS_LIB"pure_quanta_power";
"A"55;
%"Q_CAP"
"1","(-7950,4800)","0","pure_quanta","I4";
;
LOCATION"PC475"
$SEC"1"
CDS_SEC"1"
MATERIAL"X6S"
TOLERANCE"10%"
VALUE"2.2UF"
PART_NUMBER"CH5222KEB01"
VOLTAGE"10V"
PACK_TYPE"C0402"
CDS_LIB"pure_quanta";
"B"
$PN"2"10;
"A"
$PN"1"30;
%"Q_RES"
"1","(-4350,3500)","0","pure_quanta","I40";
;
LOCATION"PR324"
$SEC"1"
CDS_SEC"1"
WATTAGE"1/16W"
MATERIAL"CHIP"
TOLERANCE"5%"
VALUE"0"
PART_NUMBER"CS00002JB38"
PACK_TYPE"0402LF"
CDS_LIB"pure_quanta";
"B"
$PN"2"55;
"A"
$PN"1"32;
%"VCC_CORE"
"1","(-1275,1850)","0","pure_quanta_power","I47";
;
HDL_POWER"PVDDCR_CPU0_P0"
CDS_LIB"pure_quanta_power";
"A"48;
%"Q_CAP"
"1","(-1275,1525)","0","pure_quanta","I48";
;
LOCATION"PC501_2"
$SEC"1"
CDS_SEC"1"
MATERIAL"X6S"
TOLERANCE"20%"
VALUE"22UF"
PART_NUMBER"TMP_QCH622KMEA01"
VOLTAGE"4V"
PACK_TYPE"0805"
CDS_LIB"pure_quanta";
"B"
$PN"2"25;
"A"
$PN"1"48;
%"UNIVERSAL_GND"
"1","(-1275,1175)","0","pure_quanta_power","I49";
;
CDS_LIB"pure_quanta_power"
HDL_POWER"GND";
"A"25;
%"UNIVERSAL_GND"
"1","(-7600,5050)","0","pure_quanta_power","I5";
;
CDS_LIB"pure_quanta_power"
HDL_POWER"GND";
"A"8;
%"Q_CAP"
"1","(-1700,1525)","0","pure_quanta","I50";
;
LOCATION"PC499_2"
$SEC"1"
CDS_SEC"1"
MATERIAL"X6S"
TOLERANCE"20%"
VALUE"22UF"
PART_NUMBER"TMP_QCH622KMEA01"
VOLTAGE"4V"
PACK_TYPE"0805"
CDS_LIB"pure_quanta";
"B"
$PN"2"25;
"A"
$PN"1"48;
%"VCC_CORE"
"1","(-4250,2875)","0","pure_quanta_power","I54";
;
HDL_POWER"SW_P12V_STBY_PVDDCR_CPU0_P0_FLT"
CDS_LIB"pure_quanta_power";
"A"18;
%"UNIVERSAL_GND"
"1","(-4250,2225)","0","pure_quanta_power","I56";
;
CDS_LIB"pure_quanta_power"
HDL_POWER"GND";
"A"53;
%"VCC_CORE"
"1","(-8600,5925)","0","pure_quanta_power","I6";
;
HDL_POWER"P5V_STBY"
CDS_LIB"pure_quanta_power";
"A"9;
%"Q_CAP"
"1","(-4250,2575)","0","pure_quanta","I62";
;
LOCATION"PC488_2"
$SEC"1"
CDS_SEC"1"
TOLERANCE"10%"
MATERIAL"X6S"
PART_NUMBER"CH6104KEA00"
PACK_TYPE"C0805"
VALUE"10UF"
VOLTAGE"25V"
CDS_LIB"pure_quanta";
"B"
$PN"2"53;
"A"
$PN"1"18;
%"Q_INDUCTOR4P_14"
"1","(-3050,1575)","0","pure_quanta","I63";
;
LOCATION"PL52"
$SEC"1"
CDS_SEC"1"
PART_TYPE"SMLF"
PART_NUMBER"CV+15^0TZ04"
MATERIAL"IND"
VALUE"150NH"
NEEDS_NO_SIZE"TRUE"
CDS_LIB"pure_quanta";
"1"
$PN"1"16;
"4"
$PN"4"48;
"3"
$PN"3"26;
"2"
$PN"2"50;
%"Q_CAP"
"1","(-4550,2575)","0","pure_quanta","I64";
;
LOCATION"PC486_2"
$SEC"1"
CDS_SEC"1"
PACK_TYPE"C0805"
PART_NUMBER"CH6104KEA00"
MATERIAL"X6S"
TOLERANCE"10%"
VALUE"10UF"
VOLTAGE"25V"
CDS_LIB"pure_quanta";
"B"
$PN"2"53;
"A"
$PN"1"18;
%"Q_CAP"
"1","(-4875,2575)","0","pure_quanta","I65";
;
LOCATION"PC484_2"
$SEC"1"
CDS_SEC"1"
PART_NUMBER"CH6104KEA00"
MATERIAL"X6S"
TOLERANCE"10%"
VALUE"10UF"
VOLTAGE"25V"
PACK_TYPE"C0805"
CDS_LIB"pure_quanta";
"B"
$PN"2"53;
"A"
$PN"1"18;
%"Q_CAP"
"1","(-5200,2575)","0","pure_quanta","I66";
;
LOCATION"PC482_2"
$SEC"1"
CDS_SEC"1"
PACK_TYPE"C0402"
PART_NUMBER"CH5104KEB02"
VALUE"1UF"
MATERIAL"X6S"
TOLERANCE"10%"
VOLTAGE"25V"
CDS_LIB"pure_quanta";
"B"
$PN"2"53;
"A"
$PN"1"18;
%"Q_CAP"
"1","(-3725,1925)","0","pure_quanta","I67";
;
LOCATION"PC490"
$SEC"1"
CDS_SEC"1"
MATERIAL"X7R"
PART_NUMBER"CH4223K1B00"
TOLERANCE"10%"
VALUE"0.22UF"
VOLTAGE"16V"
PACK_TYPE"0402"
CDS_LIB"pure_quanta";
"B"
$PN"2"15;
"A"
$PN"1"49;
%"Q_RES"
"1","(-4225,775)","0","pure_quanta","I68";
;
LOCATION"PR325"
$SEC"1"
CDS_SEC"1"
WATTAGE"1/16W"
MATERIAL"CHIP"
TOLERANCE"5%"
VALUE"0"
PART_NUMBER"CS00002JB38"
PACK_TYPE"0402LF"
CDS_LIB"pure_quanta";
"B"
$PN"2"48;
"A"
$PN"1"54;
%"UNIVERSAL_GND"
"1","(-7950,4600)","0","pure_quanta_power","I7";
;
CDS_LIB"pure_quanta_power"
HDL_POWER"GND";
"A"10;
%"Q_RES"
"1","(-4700,2050)","0","pure_quanta","I71";
;
LOCATION"PR323"
$SEC"1"
CDS_SEC"1"
PACK_TYPE"0402LF"
MATERIAL"CHIP"
WATTAGE"1/16W"
TOLERANCE"1%"
VALUE"4.7"
PART_NUMBER"CS-4702FB19"
CDS_LIB"pure_quanta";
"B"
$PN"2"49;
"A"
$PN"1"17;
%"Q_RES"
"1","(-7325,1400)","0","pure_quanta","I75";
;
LOCATION"PR321"
$SEC"1"
CDS_SEC"1"
WATTAGE"1/16W"
MATERIAL"EMPTY"
TOLERANCE"1%"
VALUE"8.87K"
PART_NUMBER"CS28872FB01"
PACK_TYPE"0402LF"
CDS_LIB"pure_quanta";
"B"
$PN"2"44;
"A"
$PN"1"11;
%"UNIVERSAL_GND"
"1","(-7650,1225)","0","pure_quanta_power","I84";
;
CDS_LIB"pure_quanta_power"
HDL_POWER"GND";
"A"11;
%"UNIVERSAL_GND"
"1","(-7975,1150)","0","pure_quanta_power","I85";
;
CDS_LIB"pure_quanta_power"
HDL_POWER"GND";
"A"12;
%"Q_CAP"
"1","(-7975,1425)","0","pure_quanta","I86";
;
LOCATION"PC474_2"
$SEC"1"
CDS_SEC"1"
MATERIAL"X7R"
TOLERANCE"10%"
VALUE"0.1UF"
PART_NUMBER"CH4104K1B00"
VOLTAGE"25V"
PACK_TYPE"0402"
CDS_LIB"pure_quanta";
"B"
$PN"2"12;
"A"
$PN"1"45;
%"UNIVERSAL_GND"
"1","(-5600,975)","0","pure_quanta_power","I88";
;
CDS_LIB"pure_quanta_power"
HDL_POWER"GND";
"A"35;
%"Q_CAPP"
"1","(-2150,2900)","0","pure_quanta","I92";
;
LOCATION"PC496"
$SEC"1"
CDS_SEC"1"
VALUE"220UF"
VOLTAGE"4V"
TOLERANCE"20%"
PACK_TYPE"SMLF"
MATERIAL"SPCAP"
PART_NUMBER"CH122KM8801"
CDS_LIB"pure_quanta";
"A"
$PN"1"13;
"B"
$PN"2"14;
END.
